(kicad_pcb
	(version 20260206)
	(generator "pcbnew")
	(generator_version "10.0")
	(general
		(thickness 1.6)
		(legacy_teardrops no)
	)
	(paper "A4")
	(title_block
		(title "Bryce Canyon_IOM_IOC_16318-2_OCP.brd")
		(comment 1 "Bryce Canyon / footprints 352-358 of 1605")
	)
	(layers
		(0 "F.Cu" signal "TOP")
		(4 "In1.Cu" signal "L2GND")
		(6 "In2.Cu" signal "L3")
		(8 "In3.Cu" signal "L4VCC")
		(10 "In4.Cu" signal "L5VCC")
		(12 "In5.Cu" signal "L6")
		(14 "In6.Cu" signal "L7GND")
		(2 "B.Cu" signal "BOTTOM")
		(9 "F.Adhes" user "F.Adhesive")
		(11 "B.Adhes" user "B.Adhesive")
		(13 "F.Paste" user "Package Geometry/Pastemask Top")
		(15 "B.Paste" user "Package Geometry/Pastemask Bottom")
		(5 "F.SilkS" user "Ref Des/Silkscreen Top")
		(7 "B.SilkS" user "Ref Des/Silkscreen Bottom")
		(1 "F.Mask" user "Board Geometry/Soldermask Top")
		(3 "B.Mask" user "Board Geometry/Soldermask Bottom")
		(17 "Dwgs.User" user "User.Drawings")
		(19 "Cmts.User" user "User.Comments")
		(21 "Eco1.User" user "User.Eco1")
		(23 "Eco2.User" user "User.Eco2")
		(25 "Edge.Cuts" user "Board Geometry/Outline")
		(27 "Margin" user)
		(31 "F.CrtYd" user "Package Geometry/Place Bound Top")
		(29 "B.CrtYd" user "Package Geometry/Place Bound Bottom")
		(35 "F.Fab" user "Ref Des/Assembly Top")
		(33 "B.Fab" user "Ref Des/Assembly Bottom")
	)
	(footprint ""
		(layer "F.Cu")
		(at 60.689744 -168.952926 180)
		(property "Reference" "R75"
			(at 0 0 180)
			(layer "F.SilkS")
			(hide yes)
			(effects
				(font
					(size 1.27 1.27)
				)
			)
		)
		(property "Value" "0R2J-2-GP"
			(at 0.064008 -3.993896 180)
			(unlocked yes)
			(layer "F.Fab")
			(hide yes)
			(effects
				(font
					(size 1.016 1.016)
					(thickness 0.1524)
				)
			)
		)
		(property "Device Type" "R402H16"
			(at 0.064008 -5.517896 180)
			(unlocked yes)
			(layer "F.Fab")
			(hide yes)
			(effects
				(font
					(size 1.016 1.016)
					(thickness 0.1524)
				)
			)
		)
		(duplicate_pad_numbers_are_jumpers no)
		(fp_line
			(start 0.508 -0.9398)
			(end -0.508 -0.9398)
			(stroke
				(width 0.1524)
				(type default)
			)
			(layer "F.SilkS")
		)
		(fp_line
			(start -0.508 -0.9398)
			(end -0.508 0.9398)
			(stroke
				(width 0.1524)
				(type default)
			)
			(layer "F.SilkS")
		)
		(fp_rect
			(start -0.508 0.9398)
			(end 0.508 -0.9398)
			(stroke
				(width 0)
				(type default)
			)
			(fill no)
			(layer "F.CrtYd")
		)
		(fp_rect
			(start -0.508 0.9398)
			(end 0.508 -0.9398)
			(stroke
				(width 0)
				(type default)
			)
			(fill no)
			(layer "F.Fab")
		)
		(pad "1" smd custom
			(at 0 -0.4445 180)
			(size 0.1397 0.1397)
			(layers "F.Cu" "F.Mask" "F.Paste")
			(net "BMC_SELF_HW_RST_D")
			(options
				(clearance outline)
				(anchor circle)
			)
			(primitives
				(gr_poly
					(pts
						(arc
							(start -0.1778 -0.2794)
							(mid -0.249642 -0.249642)
							(end -0.2794 -0.1778)
						)
						(arc
							(start -0.2794 0.1778)
							(mid -0.249642 0.249642)
							(end -0.1778 0.2794)
						)
						(arc
							(start 0.1778 0.2794)
							(mid 0.249642 0.249642)
							(end 0.2794 0.1778)
						)
						(arc
							(start 0.2794 -0.1778)
							(mid 0.249642 -0.249642)
							(end 0.1778 -0.2794)
						)
					)
					(width 0)
					(fill yes)
				)
			)
		)
		(pad "2" smd custom
			(at 0 0.4445 180)
			(size 0.1397 0.1397)
			(layers "F.Cu" "F.Mask" "F.Paste")
			(net "FM_TPM_PRSNT_RST_N")
			(options
				(clearance outline)
				(anchor circle)
			)
			(primitives
				(gr_poly
					(pts
						(arc
							(start -0.1778 -0.2794)
							(mid -0.249642 -0.249642)
							(end -0.2794 -0.1778)
						)
						(arc
							(start -0.2794 0.1778)
							(mid -0.249642 0.249642)
							(end -0.1778 0.2794)
						)
						(arc
							(start 0.1778 0.2794)
							(mid 0.249642 0.249642)
							(end 0.2794 0.1778)
						)
						(arc
							(start 0.2794 -0.1778)
							(mid 0.249642 -0.249642)
							(end 0.1778 -0.2794)
						)
					)
					(width 0)
					(fill yes)
				)
			)
		)
	)
	(footprint ""
		(layer "F.Cu")
		(at 112.967516 -11.201654)
		(property "Reference" "R453"
			(at 0 0 0)
			(layer "F.SilkS")
			(hide yes)
			(effects
				(font
					(size 1.27 1.27)
				)
			)
		)
		(property "Value" "100KR2J-4-GP"
			(at 0.064008 -3.993896 0)
			(unlocked yes)
			(layer "F.Fab")
			(hide yes)
			(effects
				(font
					(size 1.016 1.016)
					(thickness 0.1524)
				)
			)
		)
		(property "Device Type" "R402H15"
			(at 0.064008 -5.517896 0)
			(unlocked yes)
			(layer "F.Fab")
			(hide yes)
			(effects
				(font
					(size 1.016 1.016)
					(thickness 0.1524)
				)
			)
		)
		(duplicate_pad_numbers_are_jumpers no)
		(fp_line
			(start -0.508 -0.9398)
			(end -0.508 0.9398)
			(stroke
				(width 0.1524)
				(type default)
			)
			(layer "F.SilkS")
		)
		(fp_line
			(start 0.508 -0.9398)
			(end -0.508 -0.9398)
			(stroke
				(width 0.1524)
				(type default)
			)
			(layer "F.SilkS")
		)
		(fp_rect
			(start -0.508 0.9398)
			(end 0.508 -0.9398)
			(stroke
				(width 0)
				(type default)
			)
			(fill no)
			(layer "F.CrtYd")
		)
		(fp_rect
			(start -0.508 0.9398)
			(end 0.508 -0.9398)
			(stroke
				(width 0)
				(type default)
			)
			(fill no)
			(layer "F.Fab")
		)
		(pad "1" smd custom
			(at 0 -0.4445)
			(size 0.1397 0.1397)
			(layers "F.Cu" "F.Mask" "F.Paste")
			(net "MB0_VCAP_R")
			(options
				(clearance outline)
				(anchor circle)
			)
			(primitives
				(gr_poly
					(pts
						(arc
							(start -0.1778 -0.2794)
							(mid -0.249642 -0.249642)
							(end -0.2794 -0.1778)
						)
						(arc
							(start -0.2794 0.1778)
							(mid -0.249642 0.249642)
							(end -0.1778 0.2794)
						)
						(arc
							(start 0.1778 0.2794)
							(mid 0.249642 0.249642)
							(end 0.2794 0.1778)
						)
						(arc
							(start 0.2794 -0.1778)
							(mid 0.249642 -0.249642)
							(end 0.1778 -0.2794)
						)
					)
					(width 0)
					(fill yes)
				)
			)
		)
		(pad "2" smd custom
			(at 0 0.4445)
			(size 0.1397 0.1397)
			(layers "F.Cu" "F.Mask" "F.Paste")
			(net "MB0_ISET_R")
			(options
				(clearance outline)
				(anchor circle)
			)
			(primitives
				(gr_poly
					(pts
						(arc
							(start -0.1778 -0.2794)
							(mid -0.249642 -0.249642)
							(end -0.2794 -0.1778)
						)
						(arc
							(start -0.2794 0.1778)
							(mid -0.249642 0.249642)
							(end -0.1778 0.2794)
						)
						(arc
							(start 0.1778 0.2794)
							(mid 0.249642 0.249642)
							(end 0.2794 0.1778)
						)
						(arc
							(start 0.2794 -0.1778)
							(mid 0.249642 -0.249642)
							(end 0.1778 -0.2794)
						)
					)
					(width 0)
					(fill yes)
				)
			)
		)
	)
	(footprint ""
		(layer "F.Cu")
		(at 93.577156 -162.51428 90)
		(property "Reference" "C20"
			(at 0 0 90)
			(layer "F.SilkS")
			(hide yes)
			(effects
				(font
					(size 1.27 1.27)
				)
			)
		)
		(property "Value" "SC18P50V2JN-1-GP"
			(at 1.1811 -2.7051 90)
			(unlocked yes)
			(layer "F.Fab")
			(hide yes)
			(effects
				(font
					(size 1.016 1.016)
					(thickness 0.1524)
				)
			)
		)
		(property "Device Type" "C402H22"
			(at 1.1811 -4.2291 90)
			(unlocked yes)
			(layer "F.Fab")
			(hide yes)
			(effects
				(font
					(size 1.016 1.016)
					(thickness 0.1524)
				)
			)
		)
		(duplicate_pad_numbers_are_jumpers no)
		(fp_rect
			(start -0.4318 0.9525)
			(end 0.4318 -0.9525)
			(stroke
				(width 0)
				(type default)
			)
			(fill no)
			(layer "F.CrtYd")
		)
		(fp_rect
			(start -0.4318 0.9525)
			(end 0.4318 -0.9525)
			(stroke
				(width 0)
				(type default)
			)
			(fill no)
			(layer "F.Fab")
		)
		(pad "1" smd custom
			(at 0 -0.4445 90)
			(size 0.1524 0.1524)
			(layers "F.Cu" "F.Mask" "F.Paste")
			(net "USB_HUB_XTAL_OUT")
			(options
				(clearance outline)
				(anchor circle)
			)
			(primitives
				(gr_poly
					(pts
						(arc
							(start 0.3048 -0.2032)
							(mid 0.275042 -0.275042)
							(end 0.2032 -0.3048)
						)
						(arc
							(start -0.2032 -0.3048)
							(mid -0.275042 -0.275042)
							(end -0.3048 -0.2032)
						)
						(arc
							(start -0.3048 0.2032)
							(mid -0.275042 0.275042)
							(end -0.2032 0.3048)
						)
						(arc
							(start 0.2032 0.3048)
							(mid 0.275042 0.275042)
							(end 0.3048 0.2032)
						)
					)
					(width 0)
					(fill yes)
				)
			)
		)
		(pad "2" smd custom
			(at 0 0.4445 90)
			(size 0.1524 0.1524)
			(layers "F.Cu" "F.Mask" "F.Paste")
			(net "GND")
			(options
				(clearance outline)
				(anchor circle)
			)
			(primitives
				(gr_poly
					(pts
						(arc
							(start 0.3048 -0.2032)
							(mid 0.275042 -0.275042)
							(end 0.2032 -0.3048)
						)
						(arc
							(start -0.2032 -0.3048)
							(mid -0.275042 -0.275042)
							(end -0.3048 -0.2032)
						)
						(arc
							(start -0.3048 0.2032)
							(mid -0.275042 0.275042)
							(end -0.2032 0.3048)
						)
						(arc
							(start 0.2032 0.3048)
							(mid 0.275042 0.275042)
							(end 0.3048 0.2032)
						)
					)
					(width 0)
					(fill yes)
				)
			)
		)
	)
	(footprint ""
		(layer "F.Cu")
		(at 21.717 -161.163)
		(property "Reference" "C227"
			(at 0 0 0)
			(layer "F.SilkS")
			(hide yes)
			(effects
				(font
					(size 1.27 1.27)
				)
			)
		)
		(property "Value" "SCD1U16V2KX-3GP"
			(at 1.1811 -2.7051 0)
			(unlocked yes)
			(layer "F.Fab")
			(hide yes)
			(effects
				(font
					(size 1.016 1.016)
					(thickness 0.1524)
				)
			)
		)
		(property "Device Type" "C402H22"
			(at 1.1811 -4.2291 0)
			(unlocked yes)
			(layer "F.Fab")
			(hide yes)
			(effects
				(font
					(size 1.016 1.016)
					(thickness 0.1524)
				)
			)
		)
		(duplicate_pad_numbers_are_jumpers no)
		(fp_rect
			(start -0.4318 0.9525)
			(end 0.4318 -0.9525)
			(stroke
				(width 0)
				(type default)
			)
			(fill no)
			(layer "F.CrtYd")
		)
		(fp_rect
			(start -0.4318 0.9525)
			(end 0.4318 -0.9525)
			(stroke
				(width 0)
				(type default)
			)
			(fill no)
			(layer "F.Fab")
		)
		(pad "1" smd custom
			(at 0 -0.4445)
			(size 0.1524 0.1524)
			(layers "F.Cu" "F.Mask" "F.Paste")
			(net "TPS74801_P1V2_STBY_OUT")
			(options
				(clearance outline)
				(anchor circle)
			)
			(primitives
				(gr_poly
					(pts
						(arc
							(start 0.3048 -0.2032)
							(mid 0.275042 -0.275042)
							(end 0.2032 -0.3048)
						)
						(arc
							(start -0.2032 -0.3048)
							(mid -0.275042 -0.275042)
							(end -0.3048 -0.2032)
						)
						(arc
							(start -0.3048 0.2032)
							(mid -0.275042 0.275042)
							(end -0.2032 0.3048)
						)
						(arc
							(start 0.2032 0.3048)
							(mid 0.275042 0.275042)
							(end 0.3048 0.2032)
						)
					)
					(width 0)
					(fill yes)
				)
			)
		)
		(pad "2" smd custom
			(at 0 0.4445)
			(size 0.1524 0.1524)
			(layers "F.Cu" "F.Mask" "F.Paste")
			(net "GND")
			(options
				(clearance outline)
				(anchor circle)
			)
			(primitives
				(gr_poly
					(pts
						(arc
							(start 0.3048 -0.2032)
							(mid 0.275042 -0.275042)
							(end 0.2032 -0.3048)
						)
						(arc
							(start -0.2032 -0.3048)
							(mid -0.275042 -0.275042)
							(end -0.3048 -0.2032)
						)
						(arc
							(start -0.3048 0.2032)
							(mid -0.275042 0.275042)
							(end -0.2032 0.3048)
						)
						(arc
							(start 0.2032 0.3048)
							(mid 0.275042 0.275042)
							(end 0.3048 0.2032)
						)
					)
					(width 0)
					(fill yes)
				)
			)
		)
	)
	(footprint ""
		(layer "F.Cu")
		(at 22.011386 -131.007358 180)
		(property "Reference" "R144"
			(at 0 0 180)
			(layer "F.SilkS")
			(hide yes)
			(effects
				(font
					(size 1.27 1.27)
				)
			)
		)
		(property "Value" "4K7R2F-GP"
			(at 0.064008 -3.993896 180)
			(unlocked yes)
			(layer "F.Fab")
			(hide yes)
			(effects
				(font
					(size 1.016 1.016)
					(thickness 0.1524)
				)
			)
		)
		(property "Device Type" "R402H16"
			(at 0.064008 -5.517896 180)
			(unlocked yes)
			(layer "F.Fab")
			(hide yes)
			(effects
				(font
					(size 1.016 1.016)
					(thickness 0.1524)
				)
			)
		)
		(duplicate_pad_numbers_are_jumpers no)
		(fp_line
			(start 0.508 -0.9398)
			(end -0.508 -0.9398)
			(stroke
				(width 0.1524)
				(type default)
			)
			(layer "F.SilkS")
		)
		(fp_line
			(start -0.508 -0.9398)
			(end -0.508 0.9398)
			(stroke
				(width 0.1524)
				(type default)
			)
			(layer "F.SilkS")
		)
		(fp_rect
			(start -0.508 0.9398)
			(end 0.508 -0.9398)
			(stroke
				(width 0)
				(type default)
			)
			(fill no)
			(layer "F.CrtYd")
		)
		(fp_rect
			(start -0.508 0.9398)
			(end 0.508 -0.9398)
			(stroke
				(width 0)
				(type default)
			)
			(fill no)
			(layer "F.Fab")
		)
		(pad "1" smd custom
			(at 0 -0.4445 180)
			(size 0.1397 0.1397)
			(layers "F.Cu" "F.Mask" "F.Paste")
			(net "DDR4_ALERT")
			(options
				(clearance outline)
				(anchor circle)
			)
			(primitives
				(gr_poly
					(pts
						(arc
							(start -0.1778 -0.2794)
							(mid -0.249642 -0.249642)
							(end -0.2794 -0.1778)
						)
						(arc
							(start -0.2794 0.1778)
							(mid -0.249642 0.249642)
							(end -0.1778 0.2794)
						)
						(arc
							(start 0.1778 0.2794)
							(mid 0.249642 0.249642)
							(end 0.2794 0.1778)
						)
						(arc
							(start 0.2794 -0.1778)
							(mid 0.249642 -0.249642)
							(end 0.1778 -0.2794)
						)
					)
					(width 0)
					(fill yes)
				)
			)
		)
		(pad "2" smd custom
			(at 0 0.4445 180)
			(size 0.1397 0.1397)
			(layers "F.Cu" "F.Mask" "F.Paste")
			(net "P1V2_STBY")
			(options
				(clearance outline)
				(anchor circle)
			)
			(primitives
				(gr_poly
					(pts
						(arc
							(start -0.1778 -0.2794)
							(mid -0.249642 -0.249642)
							(end -0.2794 -0.1778)
						)
						(arc
							(start -0.2794 0.1778)
							(mid -0.249642 0.249642)
							(end -0.1778 0.2794)
						)
						(arc
							(start 0.1778 0.2794)
							(mid 0.249642 0.249642)
							(end 0.2794 0.1778)
						)
						(arc
							(start 0.2794 -0.1778)
							(mid 0.249642 -0.249642)
							(end 0.1778 -0.2794)
						)
					)
					(width 0)
					(fill yes)
				)
			)
		)
	)
	(footprint ""
		(layer "F.Cu")
		(at 70.5104 -149.733 -90)
		(property "Reference" "U30"
			(at 0 0 270)
			(layer "F.SilkS")
			(hide yes)
			(effects
				(font
					(size 1.27 1.27)
				)
			)
		)
		(property "Value" "ICS551MLFT-GP"
			(at -3.707384 -1.5367 270)
			(unlocked yes)
			(layer "F.Fab")
			(hide yes)
			(effects
				(font
					(size 1.016 1.016)
					(thickness 0.1524)
				)
			)
		)
		(property "Device Type" "SOIC8H69"
			(at -3.707384 -3.0607 270)
			(unlocked yes)
			(layer "F.Fab")
			(hide yes)
			(effects
				(font
					(size 1.016 1.016)
					(thickness 0.1524)
				)
			)
		)
		(duplicate_pad_numbers_are_jumpers no)
		(fp_line
			(start -2.6289 3.4417)
			(end -2.6289 1.4732)
			(stroke
				(width 0.381)
				(type default)
			)
			(layer "F.SilkS")
		)
		(fp_line
			(start -2.7432 1.4224)
			(end -2.6416 1.4224)
			(stroke
				(width 0.1524)
				(type default)
			)
			(layer "F.SilkS")
		)
		(fp_line
			(start -2.7432 1.4224)
			(end 2.1336 1.4224)
			(stroke
				(width 0.1524)
				(type default)
			)
			(layer "F.SilkS")
		)
		(fp_line
			(start 2.1336 1.4224)
			(end 2.1336 -1.4224)
			(stroke
				(width 0.1524)
				(type default)
			)
			(layer "F.SilkS")
		)
		(fp_line
			(start -2.1844 -0.0508)
			(end -2.7178 0.508)
			(stroke
				(width 0.1524)
				(type default)
			)
			(layer "F.SilkS")
		)
		(fp_line
			(start -2.7178 -0.508)
			(end -2.1844 -0.0508)
			(stroke
				(width 0.1524)
				(type default)
			)
			(layer "F.SilkS")
		)
		(fp_line
			(start -2.7432 -1.4224)
			(end -2.7432 1.4224)
			(stroke
				(width 0.1524)
				(type default)
			)
			(layer "F.SilkS")
		)
		(fp_line
			(start 2.1336 -1.4224)
			(end -2.7432 -1.4224)
			(stroke
				(width 0.1524)
				(type default)
			)
			(layer "F.SilkS")
		)
		(fp_poly
			(pts
				(xy -2.2098 -1.4224) (xy -2.2098 1.4224) (xy 2.2098 1.4224) (xy 2.2098 -1.4224)
			)
			(stroke
				(width 0)
				(type default)
			)
			(fill yes)
			(layer "F.SilkS")
		)
		(fp_rect
			(start -2.450084 2.999994)
			(end 2.450084 -2.999994)
			(stroke
				(width 0)
				(type default)
			)
			(fill no)
			(layer "F.CrtYd")
		)
		(fp_poly
			(pts
				(xy -2.8194 3.6322) (xy -2.8194 -3.6322) (xy 2.8194 -3.6322) (xy 2.8194 1.18364) (xy 2.450084 1.18364)
				(xy 2.450084 -2.999994) (xy -2.450084 -2.999994) (xy -2.450084 2.999994) (xy 2.450084 2.999994)
				(xy 2.450084 1.18618) (xy 2.8194 1.18618) (xy 2.8194 3.6322)
			)
			(stroke
				(width 0)
				(type default)
			)
			(fill no)
			(layer "F.CrtYd")
		)
		(fp_rect
			(start -2.8194 3.6322)
			(end 2.8194 -3.6322)
			(stroke
				(width 0)
				(type default)
			)
			(fill no)
			(layer "F.Fab")
		)
		(pad "1" smd rect
			(at -1.905 2.54 270)
			(size 0.635 1.651)
			(layers "F.Cu" "F.Mask" "F.Paste")
			(net "50M_CLK_OUT_R")
		)
		(pad "2" smd rect
			(at -0.635 2.54 270)
			(size 0.635 1.651)
			(layers "F.Cu" "F.Mask" "F.Paste")
			(net "U30_Q1")
		)
		(pad "3" smd rect
			(at 0.635 2.54 270)
			(size 0.635 1.651)
			(layers "F.Cu" "F.Mask" "F.Paste")
			(net "Net_326")
		)
		(pad "4" smd rect
			(at 1.905 2.54 270)
			(size 0.635 1.651)
			(layers "F.Cu" "F.Mask" "F.Paste")
			(net "NCSI_RCLK_R")
		)
		(pad "5" smd rect
			(at 1.905 -2.54 270)
			(size 0.635 1.651)
			(layers "F.Cu" "F.Mask" "F.Paste")
			(net "Net_327")
		)
		(pad "6" smd rect
			(at 0.635 -2.54 270)
			(size 0.635 1.651)
			(layers "F.Cu" "F.Mask" "F.Paste")
			(net "GND")
		)
		(pad "7" smd rect
			(at -0.635 -2.54 270)
			(size 0.635 1.651)
			(layers "F.Cu" "F.Mask" "F.Paste")
			(net "P3V3_STBY")
		)
		(pad "8" smd rect
			(at -1.905 -2.54 270)
			(size 0.635 1.651)
			(layers "F.Cu" "F.Mask" "F.Paste")
			(net "50M_CLK_OE")
		)
	)
	(footprint ""
		(layer "F.Cu")
		(at 98.5266 -172.1866 -90)
		(property "Reference" "R123"
			(at 0 0 270)
			(layer "F.SilkS")
			(hide yes)
			(effects
				(font
					(size 1.27 1.27)
				)
			)
		)
		(property "Value" "0R2J-2-GP"
			(at 0.064008 -3.993896 270)
			(unlocked yes)
			(layer "F.Fab")
			(hide yes)
			(effects
				(font
					(size 1.016 1.016)
					(thickness 0.1524)
				)
			)
		)
		(property "Device Type" "R402H16"
			(at 0.064008 -5.517896 270)
			(unlocked yes)
			(layer "F.Fab")
			(hide yes)
			(effects
				(font
					(size 1.016 1.016)
					(thickness 0.1524)
				)
			)
		)
		(duplicate_pad_numbers_are_jumpers no)
		(fp_line
			(start -0.508 -0.9398)
			(end -0.508 0.9398)
			(stroke
				(width 0.1524)
				(type default)
			)
			(layer "F.SilkS")
		)
		(fp_line
			(start 0.508 -0.9398)
			(end -0.508 -0.9398)
			(stroke
				(width 0.1524)
				(type default)
			)
			(layer "F.SilkS")
		)
		(fp_rect
			(start -0.508 0.9398)
			(end 0.508 -0.9398)
			(stroke
				(width 0)
				(type default)
			)
			(fill no)
			(layer "F.CrtYd")
		)
		(fp_rect
			(start -0.508 0.9398)
			(end 0.508 -0.9398)
			(stroke
				(width 0)
				(type default)
			)
			(fill no)
			(layer "F.Fab")
		)
		(pad "1" smd custom
			(at 0 -0.4445 270)
			(size 0.1397 0.1397)
			(layers "F.Cu" "F.Mask" "F.Paste")
			(net "I2C_DPB_MISC_SDA")
			(options
				(clearance outline)
				(anchor circle)
			)
			(primitives
				(gr_poly
					(pts
						(arc
							(start -0.1778 -0.2794)
							(mid -0.249642 -0.249642)
							(end -0.2794 -0.1778)
						)
						(arc
							(start -0.2794 0.1778)
							(mid -0.249642 0.249642)
							(end -0.1778 0.2794)
						)
						(arc
							(start 0.1778 0.2794)
							(mid 0.249642 0.249642)
							(end 0.2794 0.1778)
						)
						(arc
							(start 0.2794 -0.1778)
							(mid 0.249642 -0.249642)
							(end 0.1778 -0.2794)
						)
					)
					(width 0)
					(fill yes)
				)
			)
		)
		(pad "2" smd custom
			(at 0 0.4445 270)
			(size 0.1397 0.1397)
			(layers "F.Cu" "F.Mask" "F.Paste")
			(net "I2C_DPB_MISC_SDA_R")
			(options
				(clearance outline)
				(anchor circle)
			)
			(primitives
				(gr_poly
					(pts
						(arc
							(start -0.1778 -0.2794)
							(mid -0.249642 -0.249642)
							(end -0.2794 -0.1778)
						)
						(arc
							(start -0.2794 0.1778)
							(mid -0.249642 0.249642)
							(end -0.1778 0.2794)
						)
						(arc
							(start 0.1778 0.2794)
							(mid 0.249642 0.249642)
							(end 0.2794 0.1778)
						)
						(arc
							(start 0.2794 -0.1778)
							(mid 0.249642 -0.249642)
							(end 0.1778 -0.2794)
						)
					)
					(width 0)
					(fill yes)
				)
			)
		)
	)
)
